(kicad_pcb
	(version 20241229)
	(generator "pcbnew")
	(generator_version "9.0")
	(general
		(thickness 1.61)
		(legacy_teardrops no)
	)
	(paper "A3")
	(title_block
		(title "SO-DIMM DDR5 Tester")
		(date "2025-11-26")
		(rev "1.3.0")
		(comment 9 "footprints 54-58 of 627")
	)
	(layers
		(0 "F.Cu" signal)
		(4 "In1.Cu" power)
		(6 "In2.Cu" mixed)
		(8 "In3.Cu" power)
		(10 "In4.Cu" mixed)
		(12 "In5.Cu" power)
		(14 "In6.Cu" mixed)
		(16 "In7.Cu" power)
		(18 "In8.Cu" power)
		(20 "In9.Cu" mixed)
		(22 "In10.Cu" power)
		(2 "B.Cu" signal)
		(9 "F.Adhes" user "F.Adhesive")
		(11 "B.Adhes" user "B.Adhesive")
		(13 "F.Paste" user)
		(15 "B.Paste" user)
		(5 "F.SilkS" user "F.Silkscreen")
		(7 "B.SilkS" user "B.Silkscreen")
		(1 "F.Mask" user)
		(3 "B.Mask" user)
		(17 "Dwgs.User" user "User.Drawings")
		(19 "Cmts.User" user "User.Comments")
		(21 "Eco1.User" user "User.Eco1")
		(23 "Eco2.User" user "User.Eco2")
		(25 "Edge.Cuts" user)
		(27 "Margin" user)
		(31 "F.CrtYd" user "F.Courtyard")
		(29 "B.CrtYd" user "B.Courtyard")
		(35 "F.Fab" user)
		(33 "B.Fab" user)
	)
	(footprint "antmicro-footprints:TP_SMD_1mm"
		(layer "F.Cu")
		(at 84.3 184.2)
		(property "Reference" "TP6"
			(at -2.65 0.65 0)
			(layer "F.SilkS")
			(effects
				(font
					(size 0.7 0.7)
					(thickness 0.15)
				)
				(justify left bottom)
			)
		)
		(property "Value" "TP_1mm_SMD"
			(at 0 1.4 0)
			(layer "F.Fab")
			(effects
				(font
					(size 0.7 0.7)
					(thickness 0.15)
				)
				(justify left bottom)
			)
		)
		(property "Author" "Antmicro"
			(at 0 0 0)
			(layer "F.Fab")
			(hide yes)
			(effects
				(font
					(size 1 1)
					(thickness 0.15)
				)
			)
		)
		(property "License" "Apache-2.0"
			(at 0 0 0)
			(layer "F.Fab")
			(hide yes)
			(effects
				(font
					(size 1 1)
					(thickness 0.15)
				)
			)
		)
		(property "MPN" ""
			(at 0 0 0)
			(layer "F.Fab")
			(hide yes)
			(effects
				(font
					(size 1 1)
					(thickness 0.15)
				)
			)
		)
		(property "Manufacturer" ""
			(at 0 0 0)
			(layer "F.Fab")
			(hide yes)
			(effects
				(font
					(size 1 1)
					(thickness 0.15)
				)
			)
		)
		(sheetname "/HDMI + SD Card/")
		(sheetfile "hdmi-sd-card.kicad_sch")
		(attr exclude_from_pos_files)
		(pad "1" smd circle
			(at 0 0)
			(size 1 1)
			(layers "F.Cu" "F.Mask")
			(net 329 "Net-(J4-HPD{slash}HEAC-)")
			(pinfunction "1")
			(pintype "passive")
		)
	)
	(footprint "antmicro-footprints:TP_SMD_1mm"
		(layer "F.Cu")
		(at 84.3 186.1)
		(property "Reference" "TP4"
			(at -2.65 0.65 0)
			(layer "F.SilkS")
			(effects
				(font
					(size 0.7 0.7)
					(thickness 0.15)
				)
				(justify left bottom)
			)
		)
		(property "Value" "TP_1mm_SMD"
			(at 0 1.4 0)
			(layer "F.Fab")
			(effects
				(font
					(size 0.7 0.7)
					(thickness 0.15)
				)
				(justify left bottom)
			)
		)
		(property "Author" "Antmicro"
			(at 0 0 0)
			(layer "F.Fab")
			(hide yes)
			(effects
				(font
					(size 1 1)
					(thickness 0.15)
				)
			)
		)
		(property "License" "Apache-2.0"
			(at 0 0 0)
			(layer "F.Fab")
			(hide yes)
			(effects
				(font
					(size 1 1)
					(thickness 0.15)
				)
			)
		)
		(property "MPN" ""
			(at 0 0 0)
			(layer "F.Fab")
			(hide yes)
			(effects
				(font
					(size 1 1)
					(thickness 0.15)
				)
			)
		)
		(property "Manufacturer" ""
			(at 0 0 0)
			(layer "F.Fab")
			(hide yes)
			(effects
				(font
					(size 1 1)
					(thickness 0.15)
				)
			)
		)
		(sheetname "/HDMI + SD Card/")
		(sheetfile "hdmi-sd-card.kicad_sch")
		(attr exclude_from_pos_files)
		(pad "1" smd circle
			(at 0 0)
			(size 1 1)
			(layers "F.Cu" "F.Mask")
			(net 328 "Net-(J4-SDA)")
			(pinfunction "1")
			(pintype "passive")
		)
	)
	(footprint "antmicro-footprints:TP_SMD_1mm"
		(layer "F.Cu")
		(at 85.75 183.05)
		(property "Reference" "TP2"
			(at -2.65 0.65 0)
			(layer "F.SilkS")
			(hide yes)
			(effects
				(font
					(size 0.7 0.7)
					(thickness 0.15)
				)
				(justify left bottom)
			)
		)
		(property "Value" "TP_1mm_SMD"
			(at 0 1.4 0)
			(layer "F.Fab")
			(effects
				(font
					(size 0.7 0.7)
					(thickness 0.15)
				)
				(justify left bottom)
			)
		)
		(property "Author" "Antmicro"
			(at 0 0 0)
			(layer "F.Fab")
			(hide yes)
			(effects
				(font
					(size 1 1)
					(thickness 0.15)
				)
			)
		)
		(property "License" "Apache-2.0"
			(at 0 0 0)
			(layer "F.Fab")
			(hide yes)
			(effects
				(font
					(size 1 1)
					(thickness 0.15)
				)
			)
		)
		(property "MPN" ""
			(at 0 0 0)
			(layer "F.Fab")
			(hide yes)
			(effects
				(font
					(size 1 1)
					(thickness 0.15)
				)
			)
		)
		(property "Manufacturer" ""
			(at 0 0 0)
			(layer "F.Fab")
			(hide yes)
			(effects
				(font
					(size 1 1)
					(thickness 0.15)
				)
			)
		)
		(sheetname "/HDMI + SD Card/")
		(sheetfile "hdmi-sd-card.kicad_sch")
		(attr exclude_from_pos_files)
		(pad "1" smd circle
			(at 0 0)
			(size 1 1)
			(layers "F.Cu" "F.Mask")
			(net 9 "/HDMI + SD Card/HDMI_CONN_5V")
			(pinfunction "1")
			(pintype "passive")
		)
	)
	(footprint "antmicro-footprints:HDMI-A_Receptacle_WE_685119134923"
		(layer "F.Cu")
		(at 73.020501 190.766 90)
		(property "Reference" "J4"
			(at -9.134 -3.820501 180)
			(layer "F.SilkS")
			(effects
				(font
					(size 0.7 0.7)
					(thickness 0.15)
				)
				(justify left bottom)
			)
		)
		(property "Value" "HDMI-A_WE_685119134923"
			(at 0 7.8 90)
			(layer "F.Fab")
			(effects
				(font
					(size 0.7 0.7)
					(thickness 0.15)
				)
				(justify left bottom)
			)
		)
		(property "Datasheet" "https://www.we-online.com/components/products/datasheet/685119134923.pdf"
			(at 0 0 90)
			(layer "F.Fab")
			(hide yes)
			(effects
				(font
					(size 1.27 1.27)
					(thickness 0.15)
				)
			)
		)
		(property "Author" "Antmicro"
			(at 263.786501 117.745499 0)
			(layer "F.Fab")
			(hide yes)
			(effects
				(font
					(size 1 1)
					(thickness 0.15)
				)
			)
		)
		(property "License" "Apache-2.0"
			(at 263.786501 117.745499 0)
			(layer "F.Fab")
			(hide yes)
			(effects
				(font
					(size 1 1)
					(thickness 0.15)
				)
			)
		)
		(property "MPN" "685119134923"
			(at 263.786501 117.745499 0)
			(layer "F.Fab")
			(hide yes)
			(effects
				(font
					(size 1 1)
					(thickness 0.15)
				)
			)
		)
		(property "Manufacturer" "Würth Elektronik"
			(at 263.786501 117.745499 0)
			(layer "F.Fab")
			(hide yes)
			(effects
				(font
					(size 1 1)
					(thickness 0.15)
				)
			)
		)
		(property ki_fp_filters "685119134923")
		(sheetname "/HDMI + SD Card/")
		(sheetfile "hdmi-sd-card.kicad_sch")
		(attr smd)
		(fp_line
			(start -7.55 -0.125)
			(end -7.55 2.65)
			(stroke
				(width 0.12)
				(type solid)
			)
			(layer "F.SilkS")
		)
		(fp_line
			(start 7.55 2.75)
			(end 7.55 -0.15)
			(stroke
				(width 0.12)
				(type solid)
			)
			(layer "F.SilkS")
		)
		(fp_line
			(start 5.7 5.65)
			(end 4.75 5.65)
			(stroke
				(width 0.12)
				(type solid)
			)
			(layer "F.SilkS")
		)
		(fp_line
			(start -4.85 5.65)
			(end -5.8 5.65)
			(stroke
				(width 0.12)
				(type solid)
			)
			(layer "F.SilkS")
		)
		(fp_circle
			(center -4.9 5.9)
			(end -4.85 5.9)
			(stroke
				(width 0.15)
				(type solid)
			)
			(fill no)
			(layer "F.SilkS")
		)
		(fp_rect
			(start -8.05 -6.32)
			(end 7.949 6.78)
			(stroke
				(width 0.05)
				(type solid)
			)
			(fill no)
			(layer "F.CrtYd")
		)
		(fp_line
			(start -7.05 -5.616)
			(end 6.95 -5.616)
			(stroke
				(width 0.15)
				(type solid)
			)
			(layer "F.Fab")
		)
		(fp_line
			(start -7.05 5.525)
			(end -7.05 -5.616)
			(stroke
				(width 0.15)
				(type solid)
			)
			(layer "F.Fab")
		)
		(fp_line
			(start -7.05 5.525)
			(end -6.05 6.525)
			(stroke
				(width 0.15)
				(type solid)
			)
			(layer "F.Fab")
		)
		(fp_line
			(start 6.95 6.535)
			(end 6.95 -5.616)
			(stroke
				(width 0.15)
				(type solid)
			)
			(layer "F.Fab")
		)
		(fp_line
			(start 6.95 6.535)
			(end -6.05 6.535)
			(stroke
				(width 0.15)
				(type solid)
			)
			(layer "F.Fab")
		)
		(pad "1" smd rect
			(at -4.55 5.224 90)
			(size 0.28 2.6)
			(layers "F.Cu" "F.Mask" "F.Paste")
			(net 292 "/HDMI + SD Card/HDMI_CONN_D2_P")
			(pinfunction "D2+")
			(pintype "bidirectional")
		)
		(pad "2" smd rect
			(at -4.05 5.224 90)
			(size 0.28 2.6)
			(layers "F.Cu" "F.Mask" "F.Paste")
			(net 1 "GND")
			(pinfunction "D2S")
			(pintype "passive")
		)
		(pad "3" smd rect
			(at -3.551 5.224 90)
			(size 0.28 2.6)
			(layers "F.Cu" "F.Mask" "F.Paste")
			(net 293 "/HDMI + SD Card/HDMI_CONN_D2_N")
			(pinfunction "D2-")
			(pintype "bidirectional")
		)
		(pad "4" smd rect
			(at -3.051 5.224 90)
			(size 0.28 2.6)
			(layers "F.Cu" "F.Mask" "F.Paste")
			(net 294 "/HDMI + SD Card/HDMI_CONN_D1_P")
			(pinfunction "D1+")
			(pintype "bidirectional")
		)
		(pad "5" smd rect
			(at -2.551 5.224 90)
			(size 0.28 2.6)
			(layers "F.Cu" "F.Mask" "F.Paste")
			(net 1 "GND")
			(pinfunction "D1S")
			(pintype "passive")
		)
		(pad "6" smd rect
			(at -2.05 5.224 90)
			(size 0.28 2.6)
			(layers "F.Cu" "F.Mask" "F.Paste")
			(net 295 "/HDMI + SD Card/HDMI_CONN_D1_N")
			(pinfunction "D1-")
			(pintype "bidirectional")
		)
		(pad "7" smd rect
			(at -1.551 5.224 90)
			(size 0.28 2.6)
			(layers "F.Cu" "F.Mask" "F.Paste")
			(net 296 "/HDMI + SD Card/HDMI_CONN_D0_P")
			(pinfunction "D0+")
			(pintype "bidirectional")
		)
		(pad "8" smd rect
			(at -1.051 5.224 90)
			(size 0.28 2.6)
			(layers "F.Cu" "F.Mask" "F.Paste")
			(net 1 "GND")
			(pinfunction "D0S")
			(pintype "passive")
		)
		(pad "9" smd rect
			(at -0.551 5.224 90)
			(size 0.28 2.6)
			(layers "F.Cu" "F.Mask" "F.Paste")
			(net 311 "/HDMI + SD Card/HDMI_CONN_D0_N")
			(pinfunction "D0-")
			(pintype "bidirectional")
		)
		(pad "10" smd rect
			(at -0.051 5.224 90)
			(size 0.28 2.6)
			(layers "F.Cu" "F.Mask" "F.Paste")
			(net 348 "/HDMI + SD Card/HDMI_CONN_CLK_P")
			(pinfunction "CK+")
			(pintype "bidirectional")
		)
		(pad "11" smd rect
			(at 0.45 5.224 90)
			(size 0.28 2.6)
			(layers "F.Cu" "F.Mask" "F.Paste")
			(net 1 "GND")
			(pinfunction "CKS")
			(pintype "passive")
		)
		(pad "12" smd rect
			(at 0.95 5.224 90)
			(size 0.28 2.6)
			(layers "F.Cu" "F.Mask" "F.Paste")
			(net 349 "/HDMI + SD Card/HDMI_CONN_CLK_N")
			(pinfunction "CK-")
			(pintype "bidirectional")
		)
		(pad "13" smd rect
			(at 1.449 5.224 90)
			(size 0.28 2.6)
			(layers "F.Cu" "F.Mask" "F.Paste")
			(net 325 "Net-(J4-CEC)")
			(pinfunction "CEC")
			(pintype "bidirectional")
		)
		(pad "14" smd rect
			(at 1.949 5.224 90)
			(size 0.28 2.6)
			(layers "F.Cu" "F.Mask" "F.Paste")
			(net 326 "unconnected-(J4-UTILITY{slash}HEAC+-Pad14)")
			(pinfunction "UTILITY/HEAC+")
			(pintype "bidirectional+no_connect")
		)
		(pad "15" smd rect
			(at 2.45 5.224 90)
			(size 0.28 2.6)
			(layers "F.Cu" "F.Mask" "F.Paste")
			(net 327 "Net-(J4-SCL)")
			(pinfunction "SCL")
			(pintype "bidirectional")
		)
		(pad "16" smd rect
			(at 2.95 5.224 90)
			(size 0.28 2.6)
			(layers "F.Cu" "F.Mask" "F.Paste")
			(net 328 "Net-(J4-SDA)")
			(pinfunction "SDA")
			(pintype "bidirectional")
		)
		(pad "17" smd rect
			(at 3.45 5.224 90)
			(size 0.28 2.6)
			(layers "F.Cu" "F.Mask" "F.Paste")
			(net 1 "GND")
			(pinfunction "GND")
			(pintype "power_in")
		)
		(pad "18" smd rect
			(at 3.95 5.224 90)
			(size 0.28 2.6)
			(layers "F.Cu" "F.Mask" "F.Paste")
			(net 9 "/HDMI + SD Card/HDMI_CONN_5V")
			(pinfunction "+5V")
			(pintype "power_in")
		)
		(pad "19" smd rect
			(at 4.45 5.224 90)
			(size 0.28 2.6)
			(layers "F.Cu" "F.Mask" "F.Paste")
			(net 329 "Net-(J4-HPD{slash}HEAC-)")
			(pinfunction "HPD/HEAC-")
			(pintype "bidirectional")
		)
		(pad "SH" thru_hole oval
			(at -7.3 -1.577 90)
			(size 1.5 2.7)
			(drill oval 0.9 2.1)
			(layers "*.Cu" "*.Mask")
			(remove_unused_layers no)
			(net 251 "Net-(C132-Pad1)")
			(pinfunction "SH")
			(pintype "passive")
		)
		(pad "SH" thru_hole oval
			(at -7.3 4.424 90)
			(size 1.5 3.3)
			(drill oval 0.9 2.7)
			(layers "*.Cu" "*.Mask")
			(remove_unused_layers no)
			(net 251 "Net-(C132-Pad1)")
			(pinfunction "SH")
			(pintype "passive")
		)
		(pad "SH" thru_hole oval
			(at 7.2 -1.577 90)
			(size 1.5 2.7)
			(drill oval 0.9 2.1)
			(layers "*.Cu" "*.Mask")
			(remove_unused_layers no)
			(net 251 "Net-(C132-Pad1)")
			(pinfunction "SH")
			(pintype "passive")
		)
		(pad "SH" thru_hole oval
			(at 7.2 4.424 90)
			(size 1.5 3.3)
			(drill oval 0.9 2.7)
			(layers "*.Cu" "*.Mask")
			(remove_unused_layers no)
			(net 251 "Net-(C132-Pad1)")
			(pinfunction "SH")
			(pintype "passive")
		)
	)
	(footprint "antmicro-footprints:SOD-523"
		(layer "F.Cu")
		(at 86.277001 186.1005)
		(property "Reference" "D14"
			(at 0 -0.75 0)
			(layer "F.SilkS")
			(hide yes)
			(effects
				(font
					(size 0.7 0.7)
					(thickness 0.15)
				)
				(justify left bottom)
			)
		)
		(property "Value" "BAT54-02V-G3-08"
			(at 0 1.499 0)
			(layer "F.Fab")
			(effects
				(font
					(size 0.7 0.7)
					(thickness 0.15)
				)
				(justify left bottom)
			)
		)
		(property "Datasheet" "https://www.vishay.com/docs/85633/bat5402v.pdf"
			(at 0 0 0)
			(layer "F.Fab")
			(hide yes)
			(effects
				(font
					(size 1.27 1.27)
					(thickness 0.15)
				)
			)
		)
		(property "Description" "Small Signal Schottky Diode, Single, 30 V, 200 mA, 800 mV, 600 mA, 125 °C"
			(at 0 0 0)
			(layer "F.Fab")
			(hide yes)
			(effects
				(font
					(size 1.27 1.27)
					(thickness 0.15)
				)
			)
		)
		(property "Author" "Antmicro"
			(at 0 0 0)
			(layer "F.Fab")
			(hide yes)
			(effects
				(font
					(size 1 1)
					(thickness 0.15)
				)
			)
		)
		(property "License" "Apache-2.0"
			(at 0 0 0)
			(layer "F.Fab")
			(hide yes)
			(effects
				(font
					(size 1 1)
					(thickness 0.15)
				)
			)
		)
		(property "MPN" "BAT54-02V-G3-08"
			(at 0 0 0)
			(layer "F.Fab")
			(hide yes)
			(effects
				(font
					(size 1 1)
					(thickness 0.15)
				)
			)
		)
		(property "Manufacturer" "Vishay"
			(at 0 0 0)
			(layer "F.Fab")
			(hide yes)
			(effects
				(font
					(size 1 1)
					(thickness 0.15)
				)
			)
		)
		(sheetname "/HDMI + SD Card/")
		(sheetfile "hdmi-sd-card.kicad_sch")
		(attr smd)
		(fp_line
			(start -0.35 -0.5)
			(end -0.35 0.5)
			(stroke
				(width 0.15)
				(type solid)
			)
			(layer "F.SilkS")
		)
		(fp_rect
			(start -1 -0.6)
			(end 1 0.6)
			(stroke
				(width 0.05)
				(type solid)
			)
			(fill no)
			(layer "F.CrtYd")
		)
		(fp_line
			(start -0.652 -0.425)
			(end 0.65 -0.425)
			(stroke
				(width 0.15)
				(type solid)
			)
			(layer "F.Fab")
		)
		(fp_line
			(start -0.652 0.423)
			(end -0.652 -0.425)
			(stroke
				(width 0.15)
				(type solid)
			)
			(layer "F.Fab")
		)
		(fp_line
			(start -0.652 0.423)
			(end 0.65 0.423)
			(stroke
				(width 0.15)
				(type solid)
			)
			(layer "F.Fab")
		)
		(fp_line
			(start -0.35 -0.4)
			(end -0.35 0.4)
			(stroke
				(width 0.15)
				(type solid)
			)
			(layer "F.Fab")
		)
		(fp_line
			(start 0.65 -0.425)
			(end 0.65 0.423)
			(stroke
				(width 0.15)
				(type solid)
			)
			(layer "F.Fab")
		)
		(pad "1" smd roundrect
			(at -0.701 0)
			(size 0.5 0.6)
			(layers "F.Cu" "F.Mask" "F.Paste")
			(roundrect_rratio 0.25)
			(net 9 "/HDMI + SD Card/HDMI_CONN_5V")
			(pinfunction "C")
			(pintype "passive")
		)
		(pad "2" smd roundrect
			(at 0.699 0)
			(size 0.5 0.6)
			(layers "F.Cu" "F.Mask" "F.Paste")
			(roundrect_rratio 0.25)
			(net 34 "/HDMI + SD Card/HDMI_5V")
			(pinfunction "A")
			(pintype "passive")
		)
	)
)
